(kicad_pcb
	(version 20260206)
	(generator "pcbnew")
	(generator_version "10.0")
	(general
		(thickness 1.6)
		(legacy_teardrops no)
	)
	(paper "A4")
	(title_block
		(title "01162023_DA0F0TEBIF0_F0T_Expander_BD_F_brd_V02_OCP.brd")
		(comment 1 "Grand Teton / footprints 6533-6542 of 9728")
	)
	(layers
		(0 "F.Cu" signal "TOP")
		(4 "In1.Cu" signal "GND")
		(6 "In2.Cu" signal "VCC")
		(8 "In3.Cu" signal "VCC1")
		(10 "In4.Cu" signal "GND1")
		(12 "In5.Cu" signal "IN1")
		(14 "In6.Cu" signal "GND2")
		(16 "In7.Cu" signal "IN2")
		(18 "In8.Cu" signal "GND3")
		(20 "In9.Cu" signal "IN3")
		(22 "In10.Cu" signal "GND4")
		(24 "In11.Cu" signal "IN4")
		(26 "In12.Cu" signal "GND5")
		(28 "In13.Cu" signal "IN5")
		(30 "In14.Cu" signal "GND6")
		(32 "In15.Cu" signal "IN6")
		(34 "In16.Cu" signal "GND7")
		(2 "B.Cu" signal "BOTTOM")
		(9 "F.Adhes" user "F.Adhesive")
		(11 "B.Adhes" user "B.Adhesive")
		(13 "F.Paste" user "Package Geometry/Pastemask Top")
		(15 "B.Paste" user "Package Geometry/Pastemask Bottom")
		(5 "F.SilkS" user "Ref Des/Silkscreen Top")
		(7 "B.SilkS" user "Ref Des/Silkscreen Bottom")
		(1 "F.Mask" user "Board Geometry/Soldermask Top")
		(3 "B.Mask" user "Board Geometry/Soldermask Bottom")
		(17 "Dwgs.User" user "User.Drawings")
		(19 "Cmts.User" user "User.Comments")
		(21 "Eco1.User" user "User.Eco1")
		(23 "Eco2.User" user "User.Eco2")
		(25 "Edge.Cuts" user "Board Geometry/Outline")
		(27 "Margin" user)
		(31 "F.CrtYd" user "Package Geometry/Place Bound Top")
		(29 "B.CrtYd" user "Package Geometry/Place Bound Bottom")
		(35 "F.Fab" user "Ref Des/Assembly Top")
		(33 "B.Fab" user "Ref Des/Assembly Bottom")
	)
	(footprint ""
		(layer "F.Cu")
		(at 430.961546 -151.596852 180)
		(property "Reference" "C639"
			(at 0 0 180)
			(layer "F.SilkS")
			(hide yes)
			(effects
				(font
					(size 1.27 1.27)
				)
			)
		)
		(property "Value" ""
			(at 0 0 180)
			(layer "F.Fab")
			(effects
				(font
					(size 1.27 1.27)
				)
			)
		)
		(duplicate_pad_numbers_are_jumpers no)
		(fp_line
			(start 0.299974 0.150114)
			(end -0.299974 0.150114)
			(stroke
				(width 0.1)
				(type default)
			)
			(layer "F.Fab")
		)
		(fp_line
			(start 0.299974 -0.150114)
			(end 0.299974 0.150114)
			(stroke
				(width 0.1)
				(type default)
			)
			(layer "F.Fab")
		)
		(fp_line
			(start -0.299974 0.150114)
			(end -0.299974 -0.150114)
			(stroke
				(width 0.1)
				(type default)
			)
			(layer "F.Fab")
		)
		(fp_line
			(start -0.299974 -0.150114)
			(end 0.299974 -0.150114)
			(stroke
				(width 0.1)
				(type default)
			)
			(layer "F.Fab")
		)
		(pad "1" smd rect
			(at -0.2667 0 180)
			(size 0.3048 0.381)
			(layers "F.Cu" "F.Mask" "F.Paste")
			(net "P5E_PEX3_STN0_TX_DN<13>")
		)
		(pad "2" smd rect
			(at 0.2667 0 180)
			(size 0.3048 0.381)
			(layers "F.Cu" "F.Mask" "F.Paste")
			(net "P5E_PEX3_STN0_TX_C_DN<13>")
		)
	)
	(footprint ""
		(layer "F.Cu")
		(at 260.431026 -237.165388 180)
		(property "Reference" "C4426"
			(at 0 0 180)
			(layer "F.SilkS")
			(hide yes)
			(effects
				(font
					(size 1.27 1.27)
				)
			)
		)
		(property "Value" ""
			(at 0 0 180)
			(layer "F.Fab")
			(effects
				(font
					(size 1.27 1.27)
				)
			)
		)
		(duplicate_pad_numbers_are_jumpers no)
		(fp_line
			(start 1.524 0.762)
			(end -1.524 0.762)
			(stroke
				(width 0.1524)
				(type default)
			)
			(layer "F.SilkS")
		)
		(fp_line
			(start 1.524 -0.762)
			(end 1.524 0.762)
			(stroke
				(width 0.1524)
				(type default)
			)
			(layer "F.SilkS")
		)
		(fp_line
			(start -1.524 0.762)
			(end -1.524 -0.762)
			(stroke
				(width 0.1524)
				(type default)
			)
			(layer "F.SilkS")
		)
		(fp_line
			(start -1.524 -0.762)
			(end 1.524 -0.762)
			(stroke
				(width 0.1524)
				(type default)
			)
			(layer "F.SilkS")
		)
		(fp_line
			(start 1.1049 0.724916)
			(end 1.1049 -0.724916)
			(stroke
				(width 0.1)
				(type default)
			)
			(layer "F.Fab")
		)
		(fp_line
			(start 1.1049 -0.724916)
			(end -1.1049 -0.724916)
			(stroke
				(width 0.1)
				(type default)
			)
			(layer "F.Fab")
		)
		(fp_line
			(start -1.1049 0.724916)
			(end 1.1049 0.724916)
			(stroke
				(width 0.1)
				(type default)
			)
			(layer "F.Fab")
		)
		(fp_line
			(start -1.1049 -0.724916)
			(end -1.1049 0.724916)
			(stroke
				(width 0.1)
				(type default)
			)
			(layer "F.Fab")
		)
		(pad "1" smd rect
			(at -0.889 0)
			(size 1.016 1.27)
			(layers "F.Cu" "F.Mask" "F.Paste")
			(net "P1V8_PLL0_PEX2")
		)
		(pad "2" smd rect
			(at 0.889 0)
			(size 1.016 1.27)
			(layers "F.Cu" "F.Mask" "F.Paste")
			(net "GND")
		)
	)
	(footprint ""
		(layer "F.Cu")
		(at 227.904294 -182.61838)
		(property "Reference" "Q57"
			(at -0.726694 -2.13995 0)
			(unlocked yes)
			(layer "F.SilkS")
			(effects
				(font
					(size 0.7874 0.5842)
					(thickness 0.1524)
				)
				(justify left)
			)
		)
		(property "Value" ""
			(at 0 0 0)
			(layer "F.Fab")
			(effects
				(font
					(size 1.27 1.27)
				)
			)
		)
		(duplicate_pad_numbers_are_jumpers no)
		(fp_line
			(start -1.584198 -1.53416)
			(end 1.584198 -1.53416)
			(stroke
				(width 0.1524)
				(type default)
			)
			(layer "F.SilkS")
		)
		(fp_line
			(start -1.584198 1.53416)
			(end -1.584198 -1.53416)
			(stroke
				(width 0.1524)
				(type default)
			)
			(layer "F.SilkS")
		)
		(fp_line
			(start 1.584198 -1.53416)
			(end 1.584198 1.53416)
			(stroke
				(width 0.1524)
				(type default)
			)
			(layer "F.SilkS")
		)
		(fp_line
			(start 1.584198 1.53416)
			(end -1.584198 1.53416)
			(stroke
				(width 0.1524)
				(type default)
			)
			(layer "F.SilkS")
		)
		(fp_line
			(start -0.700024 -1.500124)
			(end 0.700024 -1.500124)
			(stroke
				(width 0.1)
				(type default)
			)
			(layer "F.Fab")
		)
		(fp_line
			(start -0.700024 1.500124)
			(end -0.700024 -1.500124)
			(stroke
				(width 0.1)
				(type default)
			)
			(layer "F.Fab")
		)
		(fp_line
			(start 0.700024 -1.500124)
			(end 0.700024 1.500124)
			(stroke
				(width 0.1)
				(type default)
			)
			(layer "F.Fab")
		)
		(fp_line
			(start 0.700024 1.500124)
			(end -0.700024 1.500124)
			(stroke
				(width 0.1)
				(type default)
			)
			(layer "F.Fab")
		)
		(pad "B" smd rect
			(at -0.999998 -0.94996 90)
			(size 0.8128 0.9144)
			(layers "F.Cu" "F.Mask" "F.Paste")
			(net "RST_BJT_Q15_B")
		)
		(pad "C" smd rect
			(at 0.999998 0 90)
			(size 0.8128 0.9144)
			(layers "F.Cu" "F.Mask" "F.Paste")
			(net "RST_BJT_Q15_C")
		)
		(pad "E" smd rect
			(at -0.999998 0.94996 90)
			(size 0.8128 0.9144)
			(layers "F.Cu" "F.Mask" "F.Paste")
			(net "GND")
		)
	)
	(footprint ""
		(layer "F.Cu")
		(at 458.357732 -310.692292)
		(property "Reference" "R848"
			(at 0 0 0)
			(layer "F.SilkS")
			(hide yes)
			(effects
				(font
					(size 1.27 1.27)
				)
			)
		)
		(property "Value" ""
			(at 0 0 0)
			(layer "F.Fab")
			(effects
				(font
					(size 1.27 1.27)
				)
			)
		)
		(duplicate_pad_numbers_are_jumpers no)
		(fp_line
			(start -0.7874 -0.4064)
			(end 0.7874 -0.4064)
			(stroke
				(width 0.1524)
				(type default)
			)
			(layer "F.SilkS")
		)
		(fp_line
			(start -0.7874 0.4064)
			(end -0.7874 -0.4064)
			(stroke
				(width 0.1524)
				(type default)
			)
			(layer "F.SilkS")
		)
		(fp_line
			(start 0.7874 -0.4064)
			(end 0.7874 0.4064)
			(stroke
				(width 0.1524)
				(type default)
			)
			(layer "F.SilkS")
		)
		(fp_line
			(start 0.7874 0.4064)
			(end -0.7874 0.4064)
			(stroke
				(width 0.1524)
				(type default)
			)
			(layer "F.SilkS")
		)
		(fp_line
			(start -0.67945 -0.305054)
			(end -0.12065 -0.305054)
			(stroke
				(width 0.1)
				(type default)
			)
			(layer "F.Fab")
		)
		(fp_line
			(start -0.67945 0.3048)
			(end -0.67945 -0.305054)
			(stroke
				(width 0.1)
				(type default)
			)
			(layer "F.Fab")
		)
		(fp_line
			(start -0.12065 -0.305054)
			(end -0.12065 -0.2794)
			(stroke
				(width 0.1)
				(type default)
			)
			(layer "F.Fab")
		)
		(fp_line
			(start -0.12065 -0.2794)
			(end 0.12065 -0.2794)
			(stroke
				(width 0.1)
				(type default)
			)
			(layer "F.Fab")
		)
		(fp_line
			(start -0.12065 0.2794)
			(end -0.12065 0.3048)
			(stroke
				(width 0.1)
				(type default)
			)
			(layer "F.Fab")
		)
		(fp_line
			(start -0.12065 0.3048)
			(end -0.67945 0.3048)
			(stroke
				(width 0.1)
				(type default)
			)
			(layer "F.Fab")
		)
		(fp_line
			(start 0.120396 0.2794)
			(end -0.12065 0.2794)
			(stroke
				(width 0.1)
				(type default)
			)
			(layer "F.Fab")
		)
		(fp_line
			(start 0.120396 0.3048)
			(end 0.120396 0.2794)
			(stroke
				(width 0.1)
				(type default)
			)
			(layer "F.Fab")
		)
		(fp_line
			(start 0.12065 -0.3048)
			(end 0.67945 -0.3048)
			(stroke
				(width 0.1)
				(type default)
			)
			(layer "F.Fab")
		)
		(fp_line
			(start 0.12065 -0.2794)
			(end 0.12065 -0.3048)
			(stroke
				(width 0.1)
				(type default)
			)
			(layer "F.Fab")
		)
		(fp_line
			(start 0.67945 -0.3048)
			(end 0.67945 0.3048)
			(stroke
				(width 0.1)
				(type default)
			)
			(layer "F.Fab")
		)
		(fp_line
			(start 0.67945 0.3048)
			(end 0.120396 0.3048)
			(stroke
				(width 0.1)
				(type default)
			)
			(layer "F.Fab")
		)
		(pad "1" smd circle
			(at -0.40005 0)
			(size 0 0)
			(layers "F.Cu" "F.Mask" "F.Paste")
			(net "P1V25_PEX3_EN")
		)
		(pad "2" smd circle
			(at 0.40005 0)
			(size 0 0)
			(layers "F.Cu" "F.Mask" "F.Paste")
			(net "PWR_EN_PEX_R")
		)
	)
	(footprint ""
		(layer "F.Cu")
		(at 488.15117 -551.726608 180)
		(property "Reference" "SCREW_SSD0_2"
			(at -5.207 -1.402334 0)
			(unlocked yes)
			(layer "B.SilkS")
			(effects
				(font
					(size 0.7874 0.5842)
					(thickness 0.1524)
				)
				(justify mirror)
			)
		)
		(property "Value" ""
			(at 0 0 180)
			(layer "F.Fab")
			(effects
				(font
					(size 1.27 1.27)
				)
			)
		)
		(duplicate_pad_numbers_are_jumpers no)
		(pad "1" thru_hole circle
			(at 0 0 180)
			(size 0.4572 0.4572)
			(drill 0.2032)
			(layers "*.Cu" "*.Mask")
			(remove_unused_layers no)
			(net "Net_9155")
			(clearance 0.127)
			(thermal_gap 0.127)
			(padstack
				(mode front_inner_back)
				(layer "Inner"
					(shape circle)
					(size 0.4572 0.4572)
					(clearance 0.127)
				)
				(layer "B.Cu"
					(shape circle)
					(size 0.508 0.508)
					(clearance 0.1016)
				)
			)
		)
	)
	(footprint ""
		(layer "F.Cu")
		(at 82.661506 -124.076714 180)
		(property "Reference" "C26"
			(at 0 0 180)
			(layer "F.SilkS")
			(hide yes)
			(effects
				(font
					(size 1.27 1.27)
				)
			)
		)
		(property "Value" ""
			(at 0 0 180)
			(layer "F.Fab")
			(effects
				(font
					(size 1.27 1.27)
				)
			)
		)
		(duplicate_pad_numbers_are_jumpers no)
		(fp_line
			(start 0.299974 0.150114)
			(end -0.299974 0.150114)
			(stroke
				(width 0.1)
				(type default)
			)
			(layer "F.Fab")
		)
		(fp_line
			(start 0.299974 -0.150114)
			(end 0.299974 0.150114)
			(stroke
				(width 0.1)
				(type default)
			)
			(layer "F.Fab")
		)
		(fp_line
			(start -0.299974 0.150114)
			(end -0.299974 -0.150114)
			(stroke
				(width 0.1)
				(type default)
			)
			(layer "F.Fab")
		)
		(fp_line
			(start -0.299974 -0.150114)
			(end 0.299974 -0.150114)
			(stroke
				(width 0.1)
				(type default)
			)
			(layer "F.Fab")
		)
		(pad "1" smd rect
			(at -0.2667 0 180)
			(size 0.3048 0.381)
			(layers "F.Cu" "F.Mask" "F.Paste")
			(net "P5E_PEX0_STN0_TX_DN<3>")
		)
		(pad "2" smd rect
			(at 0.2667 0 180)
			(size 0.3048 0.381)
			(layers "F.Cu" "F.Mask" "F.Paste")
			(net "P5E_PEX0_STN0_TX_C_DN<3>")
		)
	)
	(footprint ""
		(layer "F.Cu")
		(at 220.188028 -117.90045 90)
		(property "Reference" "PC345"
			(at 0 0 90)
			(layer "F.SilkS")
			(hide yes)
			(effects
				(font
					(size 1.27 1.27)
				)
			)
		)
		(property "Value" ""
			(at 0 0 90)
			(layer "F.Fab")
			(effects
				(font
					(size 1.27 1.27)
				)
			)
		)
		(duplicate_pad_numbers_are_jumpers no)
		(fp_line
			(start 1.524 -0.762)
			(end 1.524 0.762)
			(stroke
				(width 0.1524)
				(type default)
			)
			(layer "F.SilkS")
		)
		(fp_line
			(start -1.524 -0.762)
			(end 1.524 -0.762)
			(stroke
				(width 0.1524)
				(type default)
			)
			(layer "F.SilkS")
		)
		(fp_line
			(start 1.524 0.762)
			(end -1.524 0.762)
			(stroke
				(width 0.1524)
				(type default)
			)
			(layer "F.SilkS")
		)
		(fp_line
			(start -1.524 0.762)
			(end -1.524 -0.762)
			(stroke
				(width 0.1524)
				(type default)
			)
			(layer "F.SilkS")
		)
		(fp_line
			(start 1.1049 -0.724916)
			(end -1.1049 -0.724916)
			(stroke
				(width 0.1)
				(type default)
			)
			(layer "F.Fab")
		)
		(fp_line
			(start -1.1049 -0.724916)
			(end -1.1049 0.724916)
			(stroke
				(width 0.1)
				(type default)
			)
			(layer "F.Fab")
		)
		(fp_line
			(start 1.1049 0.724916)
			(end 1.1049 -0.724916)
			(stroke
				(width 0.1)
				(type default)
			)
			(layer "F.Fab")
		)
		(fp_line
			(start -1.1049 0.724916)
			(end 1.1049 0.724916)
			(stroke
				(width 0.1)
				(type default)
			)
			(layer "F.Fab")
		)
		(pad "1" smd rect
			(at -0.889 0 270)
			(size 1.016 1.27)
			(layers "F.Cu" "F.Mask" "F.Paste")
			(net "P12V_NIC3_R")
		)
		(pad "2" smd rect
			(at 0.889 0 270)
			(size 1.016 1.27)
			(layers "F.Cu" "F.Mask" "F.Paste")
			(net "GND")
		)
	)
	(footprint ""
		(layer "F.Cu")
		(at 254.46355 -146.592798 -90)
		(property "Reference" "R733"
			(at 0 0 270)
			(layer "F.SilkS")
			(hide yes)
			(effects
				(font
					(size 1.27 1.27)
				)
			)
		)
		(property "Value" ""
			(at 0 0 270)
			(layer "F.Fab")
			(effects
				(font
					(size 1.27 1.27)
				)
			)
		)
		(duplicate_pad_numbers_are_jumpers no)
		(fp_line
			(start -0.7874 0.4064)
			(end -0.7874 -0.4064)
			(stroke
				(width 0.1524)
				(type default)
			)
			(layer "F.SilkS")
		)
		(fp_line
			(start 0.7874 0.4064)
			(end -0.7874 0.4064)
			(stroke
				(width 0.1524)
				(type default)
			)
			(layer "F.SilkS")
		)
		(fp_line
			(start -0.7874 -0.4064)
			(end 0.7874 -0.4064)
			(stroke
				(width 0.1524)
				(type default)
			)
			(layer "F.SilkS")
		)
		(fp_line
			(start 0.7874 -0.4064)
			(end 0.7874 0.4064)
			(stroke
				(width 0.1524)
				(type default)
			)
			(layer "F.SilkS")
		)
		(fp_line
			(start -0.67945 0.3048)
			(end -0.67945 -0.305054)
			(stroke
				(width 0.1)
				(type default)
			)
			(layer "F.Fab")
		)
		(fp_line
			(start -0.12065 0.3048)
			(end -0.67945 0.3048)
			(stroke
				(width 0.1)
				(type default)
			)
			(layer "F.Fab")
		)
		(fp_line
			(start 0.120396 0.3048)
			(end 0.120396 0.2794)
			(stroke
				(width 0.1)
				(type default)
			)
			(layer "F.Fab")
		)
		(fp_line
			(start 0.67945 0.3048)
			(end 0.120396 0.3048)
			(stroke
				(width 0.1)
				(type default)
			)
			(layer "F.Fab")
		)
		(fp_line
			(start -0.12065 0.2794)
			(end -0.12065 0.3048)
			(stroke
				(width 0.1)
				(type default)
			)
			(layer "F.Fab")
		)
		(fp_line
			(start 0.120396 0.2794)
			(end -0.12065 0.2794)
			(stroke
				(width 0.1)
				(type default)
			)
			(layer "F.Fab")
		)
		(fp_line
			(start -0.12065 -0.2794)
			(end 0.12065 -0.2794)
			(stroke
				(width 0.1)
				(type default)
			)
			(layer "F.Fab")
		)
		(fp_line
			(start 0.12065 -0.2794)
			(end 0.12065 -0.3048)
			(stroke
				(width 0.1)
				(type default)
			)
			(layer "F.Fab")
		)
		(fp_line
			(start 0.12065 -0.3048)
			(end 0.67945 -0.3048)
			(stroke
				(width 0.1)
				(type default)
			)
			(layer "F.Fab")
		)
		(fp_line
			(start 0.67945 -0.3048)
			(end 0.67945 0.3048)
			(stroke
				(width 0.1)
				(type default)
			)
			(layer "F.Fab")
		)
		(fp_line
			(start -0.67945 -0.305054)
			(end -0.12065 -0.305054)
			(stroke
				(width 0.1)
				(type default)
			)
			(layer "F.Fab")
		)
		(fp_line
			(start -0.12065 -0.305054)
			(end -0.12065 -0.2794)
			(stroke
				(width 0.1)
				(type default)
			)
			(layer "F.Fab")
		)
		(pad "1" smd circle
			(at -0.40005 0 270)
			(size 0 0)
			(layers "F.Cu" "F.Mask" "F.Paste")
			(net "P12V_NIC4_R")
		)
		(pad "2" smd circle
			(at 0.40005 0 270)
			(size 0 0)
			(layers "F.Cu" "F.Mask" "F.Paste")
			(net "P12V_NIC4_VIN_P")
		)
	)
	(footprint ""
		(layer "F.Cu")
		(at 242.893088 -151.737822 180)
		(property "Reference" "PR7020"
			(at 0 0 180)
			(layer "F.SilkS")
			(hide yes)
			(effects
				(font
					(size 1.27 1.27)
				)
			)
		)
		(property "Value" ""
			(at 0 0 180)
			(layer "F.Fab")
			(effects
				(font
					(size 1.27 1.27)
				)
			)
		)
		(duplicate_pad_numbers_are_jumpers no)
		(fp_line
			(start 0.7874 0.4064)
			(end -0.7874 0.4064)
			(stroke
				(width 0.1524)
				(type default)
			)
			(layer "F.SilkS")
		)
		(fp_line
			(start 0.7874 -0.4064)
			(end 0.7874 0.4064)
			(stroke
				(width 0.1524)
				(type default)
			)
			(layer "F.SilkS")
		)
		(fp_line
			(start -0.7874 0.4064)
			(end -0.7874 -0.4064)
			(stroke
				(width 0.1524)
				(type default)
			)
			(layer "F.SilkS")
		)
		(fp_line
			(start -0.7874 -0.4064)
			(end 0.7874 -0.4064)
			(stroke
				(width 0.1524)
				(type default)
			)
			(layer "F.SilkS")
		)
		(fp_line
			(start 0.67945 0.3048)
			(end 0.120396 0.3048)
			(stroke
				(width 0.1)
				(type default)
			)
			(layer "F.Fab")
		)
		(fp_line
			(start 0.67945 -0.3048)
			(end 0.67945 0.3048)
			(stroke
				(width 0.1)
				(type default)
			)
			(layer "F.Fab")
		)
		(fp_line
			(start 0.12065 -0.2794)
			(end 0.12065 -0.3048)
			(stroke
				(width 0.1)
				(type default)
			)
			(layer "F.Fab")
		)
		(fp_line
			(start 0.12065 -0.3048)
			(end 0.67945 -0.3048)
			(stroke
				(width 0.1)
				(type default)
			)
			(layer "F.Fab")
		)
		(fp_line
			(start 0.120396 0.3048)
			(end 0.120396 0.2794)
			(stroke
				(width 0.1)
				(type default)
			)
			(layer "F.Fab")
		)
		(fp_line
			(start 0.120396 0.2794)
			(end -0.12065 0.2794)
			(stroke
				(width 0.1)
				(type default)
			)
			(layer "F.Fab")
		)
		(fp_line
			(start -0.12065 0.3048)
			(end -0.67945 0.3048)
			(stroke
				(width 0.1)
				(type default)
			)
			(layer "F.Fab")
		)
		(fp_line
			(start -0.12065 0.2794)
			(end -0.12065 0.3048)
			(stroke
				(width 0.1)
				(type default)
			)
			(layer "F.Fab")
		)
		(fp_line
			(start -0.12065 -0.2794)
			(end 0.12065 -0.2794)
			(stroke
				(width 0.1)
				(type default)
			)
			(layer "F.Fab")
		)
		(fp_line
			(start -0.12065 -0.305054)
			(end -0.12065 -0.2794)
			(stroke
				(width 0.1)
				(type default)
			)
			(layer "F.Fab")
		)
		(fp_line
			(start -0.67945 0.3048)
			(end -0.67945 -0.305054)
			(stroke
				(width 0.1)
				(type default)
			)
			(layer "F.Fab")
		)
		(fp_line
			(start -0.67945 -0.305054)
			(end -0.12065 -0.305054)
			(stroke
				(width 0.1)
				(type default)
			)
			(layer "F.Fab")
		)
		(pad "1" smd circle
			(at -0.40005 0 180)
			(size 0 0)
			(layers "F.Cu" "F.Mask" "F.Paste")
			(net "P12V_NIC4_R")
		)
		(pad "2" smd circle
			(at 0.40005 0 180)
			(size 0 0)
			(layers "F.Cu" "F.Mask" "F.Paste")
			(net "P12V_NIC4_CO_AVIN_PD")
		)
	)
	(footprint ""
		(layer "F.Cu")
		(at 77.806042 -356.244906 90)
		(property "Reference" "C112"
			(at 0 0 90)
			(layer "F.SilkS")
			(hide yes)
			(effects
				(font
					(size 1.27 1.27)
				)
			)
		)
		(property "Value" ""
			(at 0 0 90)
			(layer "F.Fab")
			(effects
				(font
					(size 1.27 1.27)
				)
			)
		)
		(duplicate_pad_numbers_are_jumpers no)
		(fp_line
			(start 0.299974 -0.150114)
			(end 0.299974 0.150114)
			(stroke
				(width 0.1)
				(type default)
			)
			(layer "F.Fab")
		)
		(fp_line
			(start -0.299974 -0.150114)
			(end 0.299974 -0.150114)
			(stroke
				(width 0.1)
				(type default)
			)
			(layer "F.Fab")
		)
		(fp_line
			(start 0.299974 0.150114)
			(end -0.299974 0.150114)
			(stroke
				(width 0.1)
				(type default)
			)
			(layer "F.Fab")
		)
		(fp_line
			(start -0.299974 0.150114)
			(end -0.299974 -0.150114)
			(stroke
				(width 0.1)
				(type default)
			)
			(layer "F.Fab")
		)
		(pad "1" smd rect
			(at -0.2667 0 90)
			(size 0.3048 0.381)
			(layers "F.Cu" "F.Mask" "F.Paste")
			(net "P5E_PEX0_STN5_TX_DN<88>")
		)
		(pad "2" smd rect
			(at 0.2667 0 90)
			(size 0.3048 0.381)
			(layers "F.Cu" "F.Mask" "F.Paste")
			(net "P5E_PEX0_STN5_TX_C_DN<88>")
		)
	)
)
